(kicad_pcb
	(version 20260206)
	(generator "pcbnew")
	(generator_version "10.0")
	(general
		(thickness 1.6)
		(legacy_teardrops no)
	)
	(paper "A4")
	(title_block
		(title "Bryce Canyon_F.DPB_16315-1-OCP.brd")
		(comment 1 "Bryce Canyon / footprints 1271-1278 of 2223")
	)
	(layers
		(0 "F.Cu" signal "TOP")
		(4 "In1.Cu" signal "L2GND")
		(6 "In2.Cu" signal "L3")
		(8 "In3.Cu" signal "L4GND")
		(10 "In4.Cu" signal "L5")
		(12 "In5.Cu" signal "L6VCC")
		(14 "In6.Cu" signal "L7VCC")
		(16 "In7.Cu" signal "L8")
		(18 "In8.Cu" signal "L9GND")
		(20 "In9.Cu" signal "L10")
		(22 "In10.Cu" signal "L11GND")
		(2 "B.Cu" signal "BOTTOM")
		(9 "F.Adhes" user "F.Adhesive")
		(11 "B.Adhes" user "B.Adhesive")
		(13 "F.Paste" user "Package Geometry/Pastemask Top")
		(15 "B.Paste" user "Package Geometry/Pastemask Bottom")
		(5 "F.SilkS" user "Ref Des/Silkscreen Top")
		(7 "B.SilkS" user "Ref Des/Silkscreen Bottom")
		(1 "F.Mask" user "Board Geometry/Soldermask Top")
		(3 "B.Mask" user "Board Geometry/Soldermask Bottom")
		(17 "Dwgs.User" user "User.Drawings")
		(19 "Cmts.User" user "User.Comments")
		(21 "Eco1.User" user "User.Eco1")
		(23 "Eco2.User" user "User.Eco2")
		(25 "Edge.Cuts" user "Board Geometry/Outline")
		(27 "Margin" user)
		(31 "F.CrtYd" user "Package Geometry/Place Bound Top")
		(29 "B.CrtYd" user "Package Geometry/Place Bound Bottom")
		(35 "F.Fab" user "Ref Des/Assembly Top")
		(33 "B.Fab" user "Ref Des/Assembly Bottom")
	)
	(footprint ""
		(layer "F.Cu")
		(at 81.600548 -160.633918)
		(property "Reference" "R469"
			(at 0 0 0)
			(layer "F.SilkS")
			(hide yes)
			(effects
				(font
					(size 1.27 1.27)
				)
			)
		)
		(property "Value" "0R2J-2-GP"
			(at 0.064008 -3.993896 0)
			(unlocked yes)
			(layer "F.Fab")
			(hide yes)
			(effects
				(font
					(size 1.016 1.016)
					(thickness 0.1524)
				)
			)
		)
		(property "Device Type" "R402H16"
			(at 0.064008 -5.517896 0)
			(unlocked yes)
			(layer "F.Fab")
			(hide yes)
			(effects
				(font
					(size 1.016 1.016)
					(thickness 0.1524)
				)
			)
		)
		(duplicate_pad_numbers_are_jumpers no)
		(fp_line
			(start -0.508 -0.9398)
			(end -0.508 0.9398)
			(stroke
				(width 0.1524)
				(type default)
			)
			(layer "F.SilkS")
		)
		(fp_line
			(start 0.508 -0.9398)
			(end -0.508 -0.9398)
			(stroke
				(width 0.1524)
				(type default)
			)
			(layer "F.SilkS")
		)
		(fp_rect
			(start -0.508 0.9398)
			(end 0.508 -0.9398)
			(stroke
				(width 0)
				(type default)
			)
			(fill no)
			(layer "F.CrtYd")
		)
		(fp_rect
			(start -0.508 0.9398)
			(end 0.508 -0.9398)
			(stroke
				(width 0)
				(type default)
			)
			(fill no)
			(layer "F.Fab")
		)
		(pad "1" smd custom
			(at 0 -0.4445)
			(size 0.1397 0.1397)
			(layers "F.Cu" "F.Mask" "F.Paste")
			(net "SW_HDD_G14")
			(options
				(clearance outline)
				(anchor circle)
			)
			(primitives
				(gr_poly
					(pts
						(arc
							(start -0.1778 -0.2794)
							(mid -0.249642 -0.249642)
							(end -0.2794 -0.1778)
						)
						(arc
							(start -0.2794 0.1778)
							(mid -0.249642 0.249642)
							(end -0.1778 0.2794)
						)
						(arc
							(start 0.1778 0.2794)
							(mid 0.249642 0.249642)
							(end 0.2794 0.1778)
						)
						(arc
							(start 0.2794 -0.1778)
							(mid 0.249642 -0.249642)
							(end 0.1778 -0.2794)
						)
					)
					(width 0)
					(fill yes)
				)
			)
		)
		(pad "2" smd custom
			(at 0 0.4445)
			(size 0.1397 0.1397)
			(layers "F.Cu" "F.Mask" "F.Paste")
			(net "SW_HDD_R14")
			(options
				(clearance outline)
				(anchor circle)
			)
			(primitives
				(gr_poly
					(pts
						(arc
							(start -0.1778 -0.2794)
							(mid -0.249642 -0.249642)
							(end -0.2794 -0.1778)
						)
						(arc
							(start -0.2794 0.1778)
							(mid -0.249642 0.249642)
							(end -0.1778 0.2794)
						)
						(arc
							(start 0.1778 0.2794)
							(mid 0.249642 0.249642)
							(end 0.2794 0.1778)
						)
						(arc
							(start 0.2794 -0.1778)
							(mid 0.249642 -0.249642)
							(end 0.1778 -0.2794)
						)
					)
					(width 0)
					(fill yes)
				)
			)
		)
	)
	(footprint ""
		(layer "F.Cu")
		(at 143.999966 -94.400116)
		(property "Reference" "FLED17"
			(at 0 0 0)
			(layer "F.SilkS")
			(hide yes)
			(effects
				(font
					(size 1.27 1.27)
				)
			)
		)
		(property "Value" "LED-BY-19-GP"
			(at -2.132076 1.414018 0)
			(unlocked yes)
			(layer "F.Fab")
			(hide yes)
			(effects
				(font
					(size 1.016 1.016)
					(thickness 0.1524)
				)
			)
		)
		(property "Device Type" "LED-1615-4PH26"
			(at -2.132076 -0.109982 0)
			(unlocked yes)
			(layer "F.Fab")
			(hide yes)
			(effects
				(font
					(size 1.016 1.016)
					(thickness 0.1524)
				)
			)
		)
		(duplicate_pad_numbers_are_jumpers no)
		(fp_line
			(start -1.2954 0.254)
			(end -1.2954 1.6002)
			(stroke
				(width 0.508)
				(type default)
			)
			(layer "F.SilkS")
		)
		(fp_line
			(start -1.2954 1.6002)
			(end 1.2954 1.6002)
			(stroke
				(width 0.508)
				(type default)
			)
			(layer "F.SilkS")
		)
		(fp_line
			(start -1.1176 -1.4224)
			(end 1.1176 -1.4224)
			(stroke
				(width 0.1524)
				(type default)
			)
			(layer "F.SilkS")
		)
		(fp_line
			(start -1.1176 1.4224)
			(end -1.1176 -1.4224)
			(stroke
				(width 0.1524)
				(type default)
			)
			(layer "F.SilkS")
		)
		(fp_line
			(start 1.1176 -1.4224)
			(end 1.1176 1.4224)
			(stroke
				(width 0.1524)
				(type default)
			)
			(layer "F.SilkS")
		)
		(fp_line
			(start 1.1176 1.4224)
			(end -1.1176 1.4224)
			(stroke
				(width 0.1524)
				(type default)
			)
			(layer "F.SilkS")
		)
		(fp_line
			(start 1.2954 1.6002)
			(end 1.2954 0.254)
			(stroke
				(width 0.508)
				(type default)
			)
			(layer "F.SilkS")
		)
		(fp_rect
			(start -0.7493 0.8001)
			(end 0.7493 -0.8001)
			(stroke
				(width 0)
				(type default)
			)
			(fill no)
			(layer "F.CrtYd")
		)
		(fp_poly
			(pts
				(xy -1.3716 1.6764) (xy -1.3716 -1.6764) (xy 1.3716 -1.6764) (xy 1.3716 0.0635) (xy 0.7493 0.0635)
				(xy 0.7493 -0.8001) (xy -0.7493 -0.8001) (xy -0.7493 0.8001) (xy 0.7493 0.8001) (xy 0.7493 0.0762)
				(xy 1.3716 0.0762) (xy 1.3716 1.6764)
			)
			(stroke
				(width 0)
				(type default)
			)
			(fill no)
			(layer "F.CrtYd")
		)
		(fp_rect
			(start -1.3716 1.6764)
			(end 1.3716 -1.6764)
			(stroke
				(width 0)
				(type default)
			)
			(fill no)
			(layer "F.Fab")
		)
		(pad "1" smd rect
			(at 0.50038 -0.73025)
			(size 0.7112 0.8636)
			(layers "F.Cu" "F.Mask" "F.Paste")
			(net "DRV_ACT_16")
		)
		(pad "2" smd rect
			(at -0.50038 -0.73025)
			(size 0.7112 0.8636)
			(layers "F.Cu" "F.Mask" "F.Paste")
			(net "FLT_HDD16")
		)
		(pad "3" smd rect
			(at 0.50038 0.73025)
			(size 0.7112 0.8636)
			(layers "F.Cu" "F.Mask" "F.Paste")
			(net "DRV_ACT_16_N")
		)
		(pad "4" smd rect
			(at -0.50038 0.73025)
			(size 0.7112 0.8636)
			(layers "F.Cu" "F.Mask" "F.Paste")
			(net "FLT_HDD16_N")
		)
	)
	(footprint ""
		(layer "F.Cu")
		(at 370.259102 -286.809942 -90)
		(property "Reference" "R306"
			(at 0 0 270)
			(layer "F.SilkS")
			(hide yes)
			(effects
				(font
					(size 1.27 1.27)
				)
			)
		)
		(property "Value" "300KR2F-GP"
			(at 0.064008 -3.993896 270)
			(unlocked yes)
			(layer "F.Fab")
			(hide yes)
			(effects
				(font
					(size 1.016 1.016)
					(thickness 0.1524)
				)
			)
		)
		(property "Device Type" "R402H16"
			(at 0.064008 -5.517896 270)
			(unlocked yes)
			(layer "F.Fab")
			(hide yes)
			(effects
				(font
					(size 1.016 1.016)
					(thickness 0.1524)
				)
			)
		)
		(duplicate_pad_numbers_are_jumpers no)
		(fp_line
			(start -0.508 -0.9398)
			(end -0.508 0.9398)
			(stroke
				(width 0.1524)
				(type default)
			)
			(layer "F.SilkS")
		)
		(fp_line
			(start 0.508 -0.9398)
			(end -0.508 -0.9398)
			(stroke
				(width 0.1524)
				(type default)
			)
			(layer "F.SilkS")
		)
		(fp_rect
			(start -0.508 0.9398)
			(end 0.508 -0.9398)
			(stroke
				(width 0)
				(type default)
			)
			(fill no)
			(layer "F.CrtYd")
		)
		(fp_rect
			(start -0.508 0.9398)
			(end 0.508 -0.9398)
			(stroke
				(width 0)
				(type default)
			)
			(fill no)
			(layer "F.Fab")
		)
		(pad "1" smd custom
			(at 0 -0.4445 270)
			(size 0.1397 0.1397)
			(layers "F.Cu" "F.Mask" "F.Paste")
			(net "SW_HDD_N7")
			(options
				(clearance outline)
				(anchor circle)
			)
			(primitives
				(gr_poly
					(pts
						(arc
							(start -0.1778 -0.2794)
							(mid -0.249642 -0.249642)
							(end -0.2794 -0.1778)
						)
						(arc
							(start -0.2794 0.1778)
							(mid -0.249642 0.249642)
							(end -0.1778 0.2794)
						)
						(arc
							(start 0.1778 0.2794)
							(mid 0.249642 0.249642)
							(end 0.2794 0.1778)
						)
						(arc
							(start 0.2794 -0.1778)
							(mid 0.249642 -0.249642)
							(end 0.1778 -0.2794)
						)
					)
					(width 0)
					(fill yes)
				)
			)
		)
		(pad "2" smd custom
			(at 0 0.4445 270)
			(size 0.1397 0.1397)
			(layers "F.Cu" "F.Mask" "F.Paste")
			(net "P12V_A")
			(options
				(clearance outline)
				(anchor circle)
			)
			(primitives
				(gr_poly
					(pts
						(arc
							(start -0.1778 -0.2794)
							(mid -0.249642 -0.249642)
							(end -0.2794 -0.1778)
						)
						(arc
							(start -0.2794 0.1778)
							(mid -0.249642 0.249642)
							(end -0.1778 0.2794)
						)
						(arc
							(start 0.1778 0.2794)
							(mid 0.249642 0.249642)
							(end 0.2794 0.1778)
						)
						(arc
							(start 0.2794 -0.1778)
							(mid 0.249642 -0.249642)
							(end 0.1778 -0.2794)
						)
					)
					(width 0)
					(fill yes)
				)
			)
		)
	)
	(footprint ""
		(layer "F.Cu")
		(at 176.657 -179.683918 90)
		(property "Reference" "R522"
			(at 0 0 90)
			(layer "F.SilkS")
			(hide yes)
			(effects
				(font
					(size 1.27 1.27)
				)
			)
		)
		(property "Value" "2R6F-GP"
			(at -0.0508 -4.8514 90)
			(unlocked yes)
			(layer "F.Fab")
			(hide yes)
			(effects
				(font
					(size 1.016 1.016)
					(thickness 0.1524)
				)
			)
		)
		(property "Device Type" "R1206H26"
			(at 0 -6.3754 90)
			(unlocked yes)
			(layer "F.Fab")
			(hide yes)
			(effects
				(font
					(size 1.016 1.016)
					(thickness 0.1524)
				)
			)
		)
		(duplicate_pad_numbers_are_jumpers no)
		(fp_line
			(start 1.016 -2.2352)
			(end 1.016 2.2352)
			(stroke
				(width 0.1524)
				(type default)
			)
			(layer "F.SilkS")
		)
		(fp_line
			(start -1.016 -2.2352)
			(end 1.016 -2.2352)
			(stroke
				(width 0.1524)
				(type default)
			)
			(layer "F.SilkS")
		)
		(fp_line
			(start 1.016 2.2352)
			(end -1.016 2.2352)
			(stroke
				(width 0.1524)
				(type default)
			)
			(layer "F.SilkS")
		)
		(fp_line
			(start -1.016 2.2352)
			(end -1.016 -2.2352)
			(stroke
				(width 0.1524)
				(type default)
			)
			(layer "F.SilkS")
		)
		(fp_rect
			(start -1.0922 2.3114)
			(end 1.0922 -2.3114)
			(stroke
				(width 0)
				(type default)
			)
			(fill no)
			(layer "F.CrtYd")
		)
		(fp_poly
			(pts
				(xy -1.0922 -2.3114) (xy 1.0922 -2.3114) (xy 1.0922 2.3114) (xy -1.0922 2.3114)
			)
			(stroke
				(width 0)
				(type default)
			)
			(fill no)
			(layer "F.Fab")
		)
		(pad "1" smd rect
			(at 0 -1.397 90)
			(size 1.651 1.27)
			(layers "F.Cu" "F.Mask" "F.Paste")
			(net "P12V_HDD17")
		)
		(pad "2" smd rect
			(at 0 1.397 90)
			(size 1.651 1.27)
			(layers "F.Cu" "F.Mask" "F.Paste")
			(net "12V_PRE_17")
		)
	)
	(footprint ""
		(layer "F.Cu")
		(at 318.516 -183.620918)
		(property "Reference" "TP92"
			(at 0 0 0)
			(layer "F.SilkS")
			(hide yes)
			(effects
				(font
					(size 1.27 1.27)
				)
			)
		)
		(property "Value" "TPAD32-GP"
			(at -0.0508 -1.6764 0)
			(unlocked yes)
			(layer "F.Fab")
			(hide yes)
			(effects
				(font
					(size 1.016 1.016)
					(thickness 0.1524)
				)
			)
		)
		(property "Device Type" "TPAD32"
			(at -0.0508 -3.2004 0)
			(unlocked yes)
			(layer "F.Fab")
			(hide yes)
			(effects
				(font
					(size 1.016 1.016)
					(thickness 0.1524)
				)
			)
		)
		(duplicate_pad_numbers_are_jumpers no)
		(fp_poly
			(pts
				(arc
					(start 0.4064 0)
					(mid -0.4064 0)
					(end 0.4064 0)
				)
			)
			(stroke
				(width 0)
				(type default)
			)
			(fill no)
			(layer "F.CrtYd")
		)
		(fp_poly
			(pts
				(arc
					(start 0.7112 0)
					(mid -0.7112 0)
					(end 0.7112 0)
				)
			)
			(stroke
				(width 0)
				(type default)
			)
			(fill no)
			(layer "F.Fab")
		)
		(pad "1" smd circle
			(at 0 0)
			(size 0.8128 0.8128)
			(layers "F.Cu" "F.Mask" "F.Paste")
			(net "ACT_HDD_18")
		)
	)
	(footprint ""
		(layer "F.Cu")
		(at 161.997898 -61.127894 90)
		(property "Reference" "C410"
			(at 0 0 90)
			(layer "F.SilkS")
			(hide yes)
			(effects
				(font
					(size 1.27 1.27)
				)
			)
		)
		(property "Value" "SCD01U50V2KX-1GP"
			(at 1.1811 -2.7051 90)
			(unlocked yes)
			(layer "F.Fab")
			(hide yes)
			(effects
				(font
					(size 1.016 1.016)
					(thickness 0.1524)
				)
			)
		)
		(property "Device Type" "C402H22"
			(at 1.1811 -4.2291 90)
			(unlocked yes)
			(layer "F.Fab")
			(hide yes)
			(effects
				(font
					(size 1.016 1.016)
					(thickness 0.1524)
				)
			)
		)
		(duplicate_pad_numbers_are_jumpers no)
		(fp_rect
			(start -0.4318 0.9525)
			(end 0.4318 -0.9525)
			(stroke
				(width 0)
				(type default)
			)
			(fill no)
			(layer "F.CrtYd")
		)
		(fp_rect
			(start -0.4318 0.9525)
			(end 0.4318 -0.9525)
			(stroke
				(width 0)
				(type default)
			)
			(fill no)
			(layer "F.Fab")
		)
		(pad "1" smd custom
			(at 0 -0.4445 90)
			(size 0.1524 0.1524)
			(layers "F.Cu" "F.Mask" "F.Paste")
			(net "HDD_PRSNT_28")
			(options
				(clearance outline)
				(anchor circle)
			)
			(primitives
				(gr_poly
					(pts
						(arc
							(start 0.3048 -0.2032)
							(mid 0.275042 -0.275042)
							(end 0.2032 -0.3048)
						)
						(arc
							(start -0.2032 -0.3048)
							(mid -0.275042 -0.275042)
							(end -0.3048 -0.2032)
						)
						(arc
							(start -0.3048 0.2032)
							(mid -0.275042 0.275042)
							(end -0.2032 0.3048)
						)
						(arc
							(start 0.2032 0.3048)
							(mid 0.275042 0.275042)
							(end 0.3048 0.2032)
						)
					)
					(width 0)
					(fill yes)
				)
			)
		)
		(pad "2" smd custom
			(at 0 0.4445 90)
			(size 0.1524 0.1524)
			(layers "F.Cu" "F.Mask" "F.Paste")
			(net "GND")
			(options
				(clearance outline)
				(anchor circle)
			)
			(primitives
				(gr_poly
					(pts
						(arc
							(start 0.3048 -0.2032)
							(mid 0.275042 -0.275042)
							(end 0.2032 -0.3048)
						)
						(arc
							(start -0.2032 -0.3048)
							(mid -0.275042 -0.275042)
							(end -0.3048 -0.2032)
						)
						(arc
							(start -0.3048 0.2032)
							(mid -0.275042 0.275042)
							(end -0.2032 0.3048)
						)
						(arc
							(start 0.2032 0.3048)
							(mid 0.275042 0.275042)
							(end 0.3048 0.2032)
						)
					)
					(width 0)
					(fill yes)
				)
			)
		)
	)
	(footprint ""
		(layer "F.Cu")
		(at 395.45895 -65.826894 180)
		(property "Reference" "C457"
			(at 0 0 180)
			(layer "F.SilkS")
			(hide yes)
			(effects
				(font
					(size 1.27 1.27)
				)
			)
		)
		(property "Value" "SC10U16V6KX-2GP"
			(at -0.0762 -5.1308 180)
			(unlocked yes)
			(layer "F.Fab")
			(hide yes)
			(effects
				(font
					(size 1.016 1.016)
					(thickness 0.1524)
				)
			)
		)
		(property "Device Type" "C1206H71"
			(at -0.127 -6.6548 180)
			(unlocked yes)
			(layer "F.Fab")
			(hide yes)
			(effects
				(font
					(size 1.016 1.016)
					(thickness 0.1524)
				)
			)
		)
		(duplicate_pad_numbers_are_jumpers no)
		(fp_line
			(start 1.016 2.2352)
			(end -1.016 2.2352)
			(stroke
				(width 0.1524)
				(type default)
			)
			(layer "F.SilkS")
		)
		(fp_line
			(start 1.016 0.8382)
			(end 1.016 2.2352)
			(stroke
				(width 0.1524)
				(type default)
			)
			(layer "F.SilkS")
		)
		(fp_line
			(start 1.016 -2.2352)
			(end 1.016 -0.8382)
			(stroke
				(width 0.1524)
				(type default)
			)
			(layer "F.SilkS")
		)
		(fp_line
			(start -1.016 2.2352)
			(end -1.016 0.8382)
			(stroke
				(width 0.1524)
				(type default)
			)
			(layer "F.SilkS")
		)
		(fp_line
			(start -1.016 -0.8382)
			(end -1.016 -2.2352)
			(stroke
				(width 0.1524)
				(type default)
			)
			(layer "F.SilkS")
		)
		(fp_line
			(start -1.016 -2.2352)
			(end 1.016 -2.2352)
			(stroke
				(width 0.1524)
				(type default)
			)
			(layer "F.SilkS")
		)
		(fp_rect
			(start -1.0922 2.3114)
			(end 1.0922 -2.3114)
			(stroke
				(width 0)
				(type default)
			)
			(fill no)
			(layer "F.CrtYd")
		)
		(fp_poly
			(pts
				(xy 1.0922 -2.3114) (xy 1.0922 2.3114) (xy -1.0922 2.3114) (xy -1.0922 -2.3114)
			)
			(stroke
				(width 0)
				(type default)
			)
			(fill no)
			(layer "F.Fab")
		)
		(pad "1" smd rect
			(at 0 -1.397 180)
			(size 1.651 1.27)
			(layers "F.Cu" "F.Mask" "F.Paste")
			(net "P5V_HDD32")
		)
		(pad "2" smd rect
			(at 0 1.397 180)
			(size 1.651 1.27)
			(layers "F.Cu" "F.Mask" "F.Paste")
			(net "GND")
		)
	)
	(footprint ""
		(layer "F.Cu")
		(at 46.392846 -53.482494 -90)
		(property "Reference" "R720"
			(at 0 0 270)
			(layer "F.SilkS")
			(hide yes)
			(effects
				(font
					(size 1.27 1.27)
				)
			)
		)
		(property "Value" "300KR2F-GP"
			(at 0.064008 -3.993896 270)
			(unlocked yes)
			(layer "F.Fab")
			(hide yes)
			(effects
				(font
					(size 1.016 1.016)
					(thickness 0.1524)
				)
			)
		)
		(property "Device Type" "R402H16"
			(at 0.064008 -5.517896 270)
			(unlocked yes)
			(layer "F.Fab")
			(hide yes)
			(effects
				(font
					(size 1.016 1.016)
					(thickness 0.1524)
				)
			)
		)
		(duplicate_pad_numbers_are_jumpers no)
		(fp_line
			(start -0.508 -0.9398)
			(end -0.508 0.9398)
			(stroke
				(width 0.1524)
				(type default)
			)
			(layer "F.SilkS")
		)
		(fp_line
			(start 0.508 -0.9398)
			(end -0.508 -0.9398)
			(stroke
				(width 0.1524)
				(type default)
			)
			(layer "F.SilkS")
		)
		(fp_rect
			(start -0.508 0.9398)
			(end 0.508 -0.9398)
			(stroke
				(width 0)
				(type default)
			)
			(fill no)
			(layer "F.CrtYd")
		)
		(fp_rect
			(start -0.508 0.9398)
			(end 0.508 -0.9398)
			(stroke
				(width 0)
				(type default)
			)
			(fill no)
			(layer "F.Fab")
		)
		(pad "1" smd custom
			(at 0 -0.4445 270)
			(size 0.1397 0.1397)
			(layers "F.Cu" "F.Mask" "F.Paste")
			(net "SW_HDD_N25")
			(options
				(clearance outline)
				(anchor circle)
			)
			(primitives
				(gr_poly
					(pts
						(arc
							(start -0.1778 -0.2794)
							(mid -0.249642 -0.249642)
							(end -0.2794 -0.1778)
						)
						(arc
							(start -0.2794 0.1778)
							(mid -0.249642 0.249642)
							(end -0.1778 0.2794)
						)
						(arc
							(start 0.1778 0.2794)
							(mid 0.249642 0.249642)
							(end 0.2794 0.1778)
						)
						(arc
							(start 0.2794 -0.1778)
							(mid 0.249642 -0.249642)
							(end 0.1778 -0.2794)
						)
					)
					(width 0)
					(fill yes)
				)
			)
		)
		(pad "2" smd custom
			(at 0 0.4445 270)
			(size 0.1397 0.1397)
			(layers "F.Cu" "F.Mask" "F.Paste")
			(net "P12V_A")
			(options
				(clearance outline)
				(anchor circle)
			)
			(primitives
				(gr_poly
					(pts
						(arc
							(start -0.1778 -0.2794)
							(mid -0.249642 -0.249642)
							(end -0.2794 -0.1778)
						)
						(arc
							(start -0.2794 0.1778)
							(mid -0.249642 0.249642)
							(end -0.1778 0.2794)
						)
						(arc
							(start 0.1778 0.2794)
							(mid 0.249642 0.249642)
							(end 0.2794 0.1778)
						)
						(arc
							(start 0.2794 -0.1778)
							(mid 0.249642 -0.249642)
							(end 0.1778 -0.2794)
						)
					)
					(width 0)
					(fill yes)
				)
			)
		)
	)
)
